G04 ================== begin FILE IDENTIFICATION RECORD ==================*
G04 Layout Name:  16368-sb.brd*
G04 Film Name:    TMASK*
G04 File Format:  Gerber RS274X*
G04 File Origin:  Cadence Allegro 16.5-S056*
G04 Origin Date:  Tue Feb 07 09:07:41 2017*
G04 *
G04 Layer:  VIA CLASS/SOLDERMASK_TOP*
G04 Layer:  PIN/SOLDERMASK_TOP*
G04 Layer:  PACKAGE GEOMETRY/SOLDERMASK_TOP*
G04 Layer:  DRAWING FORMAT/LAYER_PCB_STORY*
G04 Layer:  DRAWING FORMAT/LAYER_SOLDER_T*
G04 Layer:  BOARD GEOMETRY/SOLDERMASK_TOP*
G04 *
G04 Offset:    (0.00 0.00)*
G04 Mirror:    No*
G04 Mode:      Positive*
G04 Rotation:  0*
G04 FullContactRelief:  No*
G04 UndefLineWidth:     6.00*
G04 ================== end FILE IDENTIFICATION RECORD ====================*
%FSLAX35Y35*MOIN*%
%IR0*IPPOS*OFA0.00000B0.00000*MIA0B0*SFA1.00000B1.00000*%
%AMMACRO14*
21,1,.041,.02,0.0,0.0,141.*%
%ADD14MACRO14*%
%ADD27C,.04*%
%ADD17C,.042*%
%ADD12C,.034*%
%ADD16C,.026*%
%ADD10C,.08*%
%ADD13C,.086*%
%AMMACRO35*
4,1,40,.011,-.007,
.011,.007,
.010939,.007695,
.010759,.008368,
.010464,.009,
.010064,.009571,
.009571,.010064,
.009,.010464,
.008368,.010759,
.007695,.010939,
.007,.011,
-.007,.011,
-.007695,.010939,
-.008368,.010759,
-.009,.010464,
-.009571,.010064,
-.010064,.009571,
-.010464,.009,
-.010759,.008368,
-.010939,.007695,
-.011,.007,
-.011,-.007,
-.010939,-.007695,
-.010759,-.008368,
-.010464,-.009,
-.010064,-.009571,
-.009571,-.010064,
-.009,-.010464,
-.008368,-.010759,
-.007695,-.010939,
-.007,-.011,
.007,-.011,
.007695,-.010939,
.008368,-.010759,
.009,-.010464,
.009571,-.010064,
.010064,-.009571,
.010464,-.009,
.010759,-.008368,
.010939,-.007695,
.011,-.007,
0.0*
%
%ADD35MACRO35*%
%AMMACRO22*
4,1,40,.007,.011,
-.007,.011,
-.007695,.010939,
-.008368,.010759,
-.009,.010464,
-.009571,.010064,
-.010064,.009571,
-.010464,.009,
-.010759,.008368,
-.010939,.007695,
-.011,.007,
-.011,-.007,
-.010939,-.007695,
-.010759,-.008368,
-.010464,-.009,
-.010064,-.009571,
-.009571,-.010064,
-.009,-.010464,
-.008368,-.010759,
-.007695,-.010939,
-.007,-.011,
.007,-.011,
.007695,-.010939,
.008368,-.010759,
.009,-.010464,
.009571,-.010064,
.010064,-.009571,
.010464,-.009,
.010759,-.008368,
.010939,-.007695,
.011,-.007,
.011,.007,
.010939,.007695,
.010759,.008368,
.010464,.009,
.010064,.009571,
.009571,.010064,
.009,.010464,
.008368,.010759,
.007695,.010939,
.007,.011,
0.0*
%
%ADD22MACRO22*%
%AMMACRO36*
4,1,40,.011,-.007,
.011,.007,
.010939,.007695,
.010759,.008368,
.010464,.009,
.010064,.009571,
.009571,.010064,
.009,.010464,
.008368,.010759,
.007695,.010939,
.007,.011,
-.007,.011,
-.007695,.010939,
-.008368,.010759,
-.009,.010464,
-.009571,.010064,
-.010064,.009571,
-.010464,.009,
-.010759,.008368,
-.010939,.007695,
-.011,.007,
-.011,-.007,
-.010939,-.007695,
-.010759,-.008368,
-.010464,-.009,
-.010064,-.009571,
-.009571,-.010064,
-.009,-.010464,
-.008368,-.010759,
-.007695,-.010939,
-.007,-.011,
.007,-.011,
.007695,-.010939,
.008368,-.010759,
.009,-.010464,
.009571,-.010064,
.010064,-.009571,
.010464,-.009,
.010759,-.008368,
.010939,-.007695,
.011,-.007,
0.0*
%
%ADD36MACRO36*%
%AMMACRO23*
4,1,40,.007,.011,
-.007,.011,
-.007695,.010939,
-.008368,.010759,
-.009,.010464,
-.009571,.010064,
-.010064,.009571,
-.010464,.009,
-.010759,.008368,
-.010939,.007695,
-.011,.007,
-.011,-.007,
-.010939,-.007695,
-.010759,-.008368,
-.010464,-.009,
-.010064,-.009571,
-.009571,-.010064,
-.009,-.010464,
-.008368,-.010759,
-.007695,-.010939,
-.007,-.011,
.007,-.011,
.007695,-.010939,
.008368,-.010759,
.009,-.010464,
.009571,-.010064,
.010064,-.009571,
.010464,-.009,
.010759,-.008368,
.010939,-.007695,
.011,-.007,
.011,.007,
.010939,.007695,
.010759,.008368,
.010464,.009,
.010064,.009571,
.009571,.010064,
.009,.010464,
.008368,.010759,
.007695,.010939,
.007,.011,
0.0*
%
%ADD23MACRO23*%
%ADD28O,.04X.023*%
%ADD32R,.04X.022*%
%ADD29R,.032X.022*%
%ADD18R,.012X.033*%
%AMMACRO15*
21,1,.041,.02,0.0,0.0,39.*%
%ADD15MACRO15*%
%ADD25R,.048X.016*%
%ADD26R,.016X.048*%
%ADD31R,.063X.038*%
%ADD11C,.165*%
%ADD24R,.073X.049*%
%AMMACRO34*
4,1,40,-.008,-.012,
.008,-.012,
.008695,-.011939,
.009368,-.011759,
.01,-.011464,
.010571,-.011064,
.011064,-.010571,
.011464,-.01,
.011759,-.009368,
.011939,-.008695,
.012,-.008,
.012,.008,
.011939,.008695,
.011759,.009368,
.011464,.01,
.011064,.010571,
.010571,.011064,
.01,.011464,
.009368,.011759,
.008695,.011939,
.008,.012,
-.008,.012,
-.008695,.011939,
-.009368,.011759,
-.01,.011464,
-.010571,.011064,
-.011064,.010571,
-.011464,.01,
-.011759,.009368,
-.011939,.008695,
-.012,.008,
-.012,-.008,
-.011939,-.008695,
-.011759,-.009368,
-.011464,-.01,
-.011064,-.010571,
-.010571,-.011064,
-.01,-.011464,
-.009368,-.011759,
-.008695,-.011939,
-.008,-.012,
0.0*
%
%ADD34MACRO34*%
%AMMACRO19*
4,1,40,-.007,-.011,
.007,-.011,
.007695,-.010939,
.008368,-.010759,
.009,-.010464,
.009571,-.010064,
.010064,-.009571,
.010464,-.009,
.010759,-.008368,
.010939,-.007695,
.011,-.007,
.011,.007,
.010939,.007695,
.010759,.008368,
.010464,.009,
.010064,.009571,
.009571,.010064,
.009,.010464,
.008368,.010759,
.007695,.010939,
.007,.011,
-.007,.011,
-.007695,.010939,
-.008368,.010759,
-.009,.010464,
-.009571,.010064,
-.010064,.009571,
-.010464,.009,
-.010759,.008368,
-.010939,.007695,
-.011,.007,
-.011,-.007,
-.010939,-.007695,
-.010759,-.008368,
-.010464,-.009,
-.010064,-.009571,
-.009571,-.010064,
-.009,-.010464,
-.008368,-.010759,
-.007695,-.010939,
-.007,-.011,
0.0*
%
%ADD19MACRO19*%
%AMMACRO21*
4,1,40,-.011,.007,
-.011,-.007,
-.010939,-.007695,
-.010759,-.008368,
-.010464,-.009,
-.010064,-.009571,
-.009571,-.010064,
-.009,-.010464,
-.008368,-.010759,
-.007695,-.010939,
-.007,-.011,
.007,-.011,
.007695,-.010939,
.008368,-.010759,
.009,-.010464,
.009571,-.010064,
.010064,-.009571,
.010464,-.009,
.010759,-.008368,
.010939,-.007695,
.011,-.007,
.011,.007,
.010939,.007695,
.010759,.008368,
.010464,.009,
.010064,.009571,
.009571,.010064,
.009,.010464,
.008368,.010759,
.007695,.010939,
.007,.011,
-.007,.011,
-.007695,.010939,
-.008368,.010759,
-.009,.010464,
-.009571,.010064,
-.010064,.009571,
-.010464,.009,
-.010759,.008368,
-.010939,.007695,
-.011,.007,
0.0*
%
%ADD21MACRO21*%
%AMMACRO33*
4,1,40,-.008,-.012,
.008,-.012,
.008695,-.011939,
.009368,-.011759,
.01,-.011464,
.010571,-.011064,
.011064,-.010571,
.011464,-.01,
.011759,-.009368,
.011939,-.008695,
.012,-.008,
.012,.008,
.011939,.008695,
.011759,.009368,
.011464,.01,
.011064,.010571,
.010571,.011064,
.01,.011464,
.009368,.011759,
.008695,.011939,
.008,.012,
-.008,.012,
-.008695,.011939,
-.009368,.011759,
-.01,.011464,
-.010571,.011064,
-.011064,.010571,
-.011464,.01,
-.011759,.009368,
-.011939,.008695,
-.012,.008,
-.012,-.008,
-.011939,-.008695,
-.011759,-.009368,
-.011464,-.01,
-.011064,-.010571,
-.010571,-.011064,
-.01,-.011464,
-.009368,-.011759,
-.008695,-.011939,
-.008,-.012,
0.0*
%
%ADD33MACRO33*%
%AMMACRO20*
4,1,40,-.007,-.011,
.007,-.011,
.007695,-.010939,
.008368,-.010759,
.009,-.010464,
.009571,-.010064,
.010064,-.009571,
.010464,-.009,
.010759,-.008368,
.010939,-.007695,
.011,-.007,
.011,.007,
.010939,.007695,
.010759,.008368,
.010464,.009,
.010064,.009571,
.009571,.010064,
.009,.010464,
.008368,.010759,
.007695,.010939,
.007,.011,
-.007,.011,
-.007695,.010939,
-.008368,.010759,
-.009,.010464,
-.009571,.010064,
-.010064,.009571,
-.010464,.009,
-.010759,.008368,
-.010939,.007695,
-.011,.007,
-.011,-.007,
-.010939,-.007695,
-.010759,-.008368,
-.010464,-.009,
-.010064,-.009571,
-.009571,-.010064,
-.009,-.010464,
-.008368,-.010759,
-.007695,-.010939,
-.007,-.011,
0.0*
%
%ADD20MACRO20*%
%AMMACRO30*
4,1,40,-.011,.007,
-.011,-.007,
-.010939,-.007695,
-.010759,-.008368,
-.010464,-.009,
-.010064,-.009571,
-.009571,-.010064,
-.009,-.010464,
-.008368,-.010759,
-.007695,-.010939,
-.007,-.011,
.007,-.011,
.007695,-.010939,
.008368,-.010759,
.009,-.010464,
.009571,-.010064,
.010064,-.009571,
.010464,-.009,
.010759,-.008368,
.010939,-.007695,
.011,-.007,
.011,.007,
.010939,.007695,
.010759,.008368,
.010464,.009,
.010064,.009571,
.009571,.010064,
.009,.010464,
.008368,.010759,
.007695,.010939,
.007,.011,
-.007,.011,
-.007695,.010939,
-.008368,.010759,
-.009,.010464,
-.009571,.010064,
-.010064,.009571,
-.010464,.009,
-.010759,.008368,
-.010939,.007695,
-.011,.007,
0.0*
%
%ADD30MACRO30*%
%ADD37C,.02*%
%ADD38C,.006*%
%ADD39C,.197*%
G75*
%LPD*%
G75*
G36*
G01X33467Y19685D02*
G02I-15750J0D01*
G37*
G36*
G01X175199D02*
G02I-15750J0D01*
G37*
%LPC*%
G75*
G54D39*
X17717Y19685D03*
X159449D03*
%LPD*%
G75*
G54D10*
X25827Y-9492D03*
X141000Y43000D03*
X519227Y-9492D03*
G54D20*
X58800Y25000D03*
X101800Y21000D03*
X59300D03*
X101300Y29500D03*
X54300Y29000D03*
X79800Y37500D03*
G54D11*
X17717Y19685D03*
X159449D03*
G54D30*
X83500Y33200D03*
X133500Y22200D03*
G54D21*
X83500Y29800D03*
X133500Y18800D03*
G54D12*
X28802Y13285D03*
X24117Y8600D03*
X11317D03*
X6632Y13285D03*
Y26085D03*
X11317Y30770D03*
X24117D03*
X28802Y26085D03*
X170534Y13285D03*
X165849Y8600D03*
X153049D03*
X148364Y13285D03*
Y26085D03*
X153049Y30770D03*
X165849D03*
X170534Y26085D03*
G54D31*
X71000Y50200D03*
Y42800D03*
G54D22*
X101300Y25500D03*
X46300Y21000D03*
X88800D03*
X77300D03*
G54D13*
X9000Y48000D03*
X164500Y48500D03*
G54D32*
X89000Y49000D03*
X80000D03*
G54D23*
X104700Y25500D03*
X49700Y21000D03*
X92200D03*
X80700D03*
G54D14*
X26811Y43012D03*
X56497Y50886D03*
G54D33*
X64500Y42200D03*
G54D24*
X118110Y4456D03*
Y15230D03*
X103937Y4456D03*
Y15230D03*
X89764Y4456D03*
Y15230D03*
X75591Y4456D03*
Y15230D03*
X61417Y4456D03*
Y15230D03*
X47244Y4456D03*
Y15230D03*
G54D15*
X26811Y50886D03*
X56497Y43012D03*
G54D34*
X64500Y45800D03*
G54D25*
X68750Y29500D03*
Y26940D03*
X75250D03*
X68750Y32060D03*
X75250D03*
G54D16*
X26890Y46949D03*
X62500Y29600D03*
X46000Y25600D03*
X111800Y52264D03*
X96000Y55600D03*
X111700Y39600D03*
X99000Y46500D03*
X78000Y42500D03*
X127500Y52264D03*
Y37000D03*
G54D26*
X88940Y28250D03*
X94060D03*
X116060Y30250D03*
X113500D03*
X110940D03*
Y23750D03*
X116060D03*
X94060Y34750D03*
X91500D03*
X88940D03*
X128060Y30250D03*
X125500D03*
X122940D03*
Y23750D03*
X128060D03*
G54D35*
X126000Y17200D03*
X133500Y29700D03*
G54D17*
X32205Y38484D03*
Y55414D03*
X51103Y38484D03*
Y55414D03*
G54D18*
X30827Y43681D03*
X32796D03*
Y50217D03*
X30827D03*
X34764Y43681D03*
X36733D03*
X38701D03*
X40670D03*
X42638D03*
X44607D03*
X46575D03*
X48544D03*
X50512D03*
X52481D03*
Y50217D03*
X50512D03*
X48544D03*
X46575D03*
X44607D03*
X42638D03*
X40670D03*
X38701D03*
X36733D03*
X34764D03*
G54D36*
X126000Y13800D03*
X133500Y26300D03*
G54D27*
X103642Y43898D03*
X127264D03*
G54D37*
G01X-149983Y-76117D02*
Y-156117D01*
G01D02*
X864117D01*
G01X-153983Y-60117D02*
G02I-12000J0D01*
G01X-159133D02*
G02I-6850J0D01*
G01X-165983Y-76117D02*
Y-44117D01*
G01X-149983Y-60117D02*
X-181983D01*
G01X-149983Y-76117D02*
X864117D01*
G01X-149983Y-111617D02*
X864117D01*
G01X76617Y-76117D02*
Y-156117D01*
G01X214117Y-76117D02*
Y-156117D01*
G01X329117Y-76117D02*
Y-156117D01*
G01X496617Y-76117D02*
Y-156117D01*
G01X666617Y-76117D02*
Y-156117D01*
G01X864117Y-76117D02*
Y-156117D01*
G01X892117Y-60117D02*
G02I-12000J0D01*
G01X886967D02*
G02I-6850J0D01*
G01X880117Y-76117D02*
Y-44117D01*
G01X896117Y-60117D02*
X864117D01*
G54D19*
X62200Y25000D03*
X105200Y21000D03*
X62700D03*
X104700Y29500D03*
X57700Y29000D03*
X83200Y37500D03*
G54D28*
X56418Y46949D03*
G54D38*
G01X-137600Y-128617D02*
Y-146117D01*
X-128866D01*
G01X-113987Y-136784D02*
X-113113Y-135909D01*
X-112458Y-134451D01*
X-112021Y-132408D01*
X-112458Y-130659D01*
X-113331Y-129492D01*
X-114860Y-128617D01*
X-120755D01*
Y-146117D01*
X-113550D01*
X-112021Y-144951D01*
X-111148Y-143200D01*
X-110711Y-141159D01*
X-111148Y-139117D01*
X-112458Y-137367D01*
X-113987Y-136784D01*
X-120755D01*
G01X-93430Y-130076D02*
X-94740Y-129200D01*
X-96268Y-128617D01*
X-98015D01*
X-99980Y-129492D01*
X-101508Y-130950D01*
X-102600Y-132701D01*
X-103473Y-135617D01*
X-103692Y-138242D01*
X-103255Y-140867D01*
X-102600Y-142617D01*
X-101290Y-144367D01*
X-99761Y-145534D01*
X-98233Y-146117D01*
X-96705D01*
X-95176Y-145534D01*
X-93866Y-144659D01*
X-92774Y-143493D01*
G01X-67600Y-128617D02*
Y-146117D01*
X-58866D01*
G01X-41366D02*
X-50100D01*
Y-128617D01*
X-41366D01*
G01X-44860Y-137075D02*
X-50100D01*
G01X-33036Y-146117D02*
Y-128617D01*
X-28670D01*
X-26923Y-129492D01*
X-25613Y-130659D01*
X-24521Y-132408D01*
X-23648Y-134451D01*
X-23430Y-137367D01*
X-23648Y-140284D01*
X-24521Y-142326D01*
X-25613Y-144076D01*
X-26923Y-145242D01*
X-28670Y-146117D01*
X-33036D01*
G01X10260Y-135909D02*
X8732Y-134742D01*
X7422Y-134451D01*
X5675Y-135034D01*
X4365Y-136200D01*
X3492Y-138242D01*
X3273Y-140284D01*
X3492Y-142326D01*
X4365Y-144076D01*
X5675Y-145534D01*
X7422Y-146117D01*
X8950Y-145534D01*
X10260Y-144367D01*
G01X28197Y-146117D02*
Y-134451D01*
G01Y-136492D02*
X27324Y-135326D01*
X26013Y-134742D01*
X24485Y-134451D01*
X22957Y-135034D01*
X21647Y-136200D01*
X20773Y-137950D01*
X20337Y-140284D01*
X20773Y-142617D01*
X21647Y-144367D01*
X22957Y-145534D01*
X24485Y-146117D01*
X26013Y-145825D01*
X27324Y-144951D01*
X28197Y-143784D01*
G01X38710Y-146117D02*
Y-134451D01*
G01Y-136784D02*
X39802Y-135617D01*
X40894Y-134742D01*
X42422Y-134451D01*
X43513Y-134742D01*
X44824Y-135617D01*
G01X63197Y-128617D02*
Y-146117D01*
G01Y-143493D02*
X62324Y-144951D01*
X61013Y-145825D01*
X59485Y-146117D01*
X57739Y-145534D01*
X56429Y-144076D01*
X55555Y-142326D01*
X55337Y-140284D01*
X55555Y-138242D01*
X56429Y-136492D01*
X57739Y-135034D01*
X59485Y-134451D01*
X61013Y-134742D01*
X62105Y-135326D01*
X63197Y-136492D01*
G01X-77660Y-101117D02*
Y-83617D01*
X-71983Y-98200D01*
X-66306Y-83617D01*
Y-101117D01*
G01X-54483D02*
X-55793Y-100825D01*
X-57103Y-99659D01*
X-57977Y-97617D01*
X-58413Y-95284D01*
X-57977Y-92950D01*
X-57103Y-90909D01*
X-55793Y-89742D01*
X-54483Y-89451D01*
X-53173Y-89742D01*
X-51863Y-90909D01*
X-50990Y-92950D01*
X-50771Y-95284D01*
X-50990Y-97617D01*
X-51863Y-99659D01*
X-53173Y-100825D01*
X-54483Y-101117D01*
G01X-33053Y-83617D02*
Y-101117D01*
G01Y-98493D02*
X-33926Y-99951D01*
X-35237Y-100825D01*
X-36765Y-101117D01*
X-38511Y-100534D01*
X-39821Y-99076D01*
X-40695Y-97326D01*
X-40913Y-95284D01*
X-40695Y-93242D01*
X-39821Y-91492D01*
X-38511Y-90034D01*
X-36765Y-89451D01*
X-35237Y-89742D01*
X-34145Y-90326D01*
X-33053Y-91492D01*
G01X-22758Y-93242D02*
X-15771D01*
X-16426Y-91200D01*
X-17518Y-90034D01*
X-19046Y-89451D01*
X-20575Y-89742D01*
X-21885Y-90617D01*
X-22758Y-92659D01*
X-23195Y-94409D01*
Y-96159D01*
X-22758Y-97909D01*
X-21666Y-99659D01*
X-20356Y-100825D01*
X-18828Y-101117D01*
X-17300Y-100534D01*
X-15771Y-98784D01*
G01X-1983Y-101117D02*
Y-83617D01*
G01X110317Y-146117D02*
Y-128617D01*
X107697Y-132117D01*
G01Y-146117D02*
X112937D01*
G01X123669Y-138826D02*
X125197Y-136784D01*
X126507Y-135617D01*
X128254Y-135034D01*
X129782Y-135617D01*
X130874Y-136784D01*
X131747Y-138534D01*
X131965Y-140575D01*
X131747Y-142326D01*
X130874Y-144076D01*
X129563Y-145534D01*
X128035Y-146117D01*
X126289Y-145534D01*
X124760Y-143784D01*
X123887Y-141159D01*
X123669Y-138242D01*
X124105Y-134451D01*
X124760Y-132408D01*
X125852Y-130367D01*
X127380Y-128909D01*
X128909Y-128617D01*
X130437Y-129200D01*
X131529Y-130659D01*
G01X140514Y-142617D02*
X141823Y-144659D01*
X143570Y-145825D01*
X145535Y-146117D01*
X147282Y-145825D01*
X149029Y-144367D01*
X150120Y-142617D01*
X150339Y-140867D01*
X149902Y-138826D01*
X148374Y-137367D01*
X146845Y-136784D01*
X144880D01*
G01X146845D02*
X148155Y-135909D01*
X149247Y-134451D01*
X149684Y-132701D01*
X149247Y-130950D01*
X148155Y-129492D01*
X146190Y-128617D01*
X144225Y-128909D01*
X142260Y-130076D01*
G01X158669Y-138826D02*
X160197Y-136784D01*
X161507Y-135617D01*
X163254Y-135034D01*
X164782Y-135617D01*
X165874Y-136784D01*
X166747Y-138534D01*
X166965Y-140575D01*
X166747Y-142326D01*
X165874Y-144076D01*
X164563Y-145534D01*
X163035Y-146117D01*
X161289Y-145534D01*
X159760Y-143784D01*
X158887Y-141159D01*
X158669Y-138242D01*
X159105Y-134451D01*
X159760Y-132408D01*
X160852Y-130367D01*
X162380Y-128909D01*
X163909Y-128617D01*
X165437Y-129200D01*
X166529Y-130659D01*
G01X180317Y-146117D02*
X181845Y-145825D01*
X183592Y-144951D01*
X184684Y-143493D01*
X185120Y-141450D01*
X184684Y-139409D01*
X183374Y-137659D01*
X181409Y-136784D01*
X179225D01*
X177915Y-136200D01*
X176823Y-134742D01*
X176387Y-132701D01*
X177042Y-130659D01*
X178570Y-129200D01*
X180317Y-128617D01*
X182063Y-129200D01*
X183592Y-130659D01*
X184247Y-132701D01*
X183810Y-134742D01*
X182719Y-136200D01*
X181409Y-136784D01*
X179225D01*
X177260Y-137659D01*
X175950Y-139409D01*
X175514Y-141450D01*
X175950Y-143493D01*
X177042Y-144951D01*
X178789Y-145825D01*
X180317Y-146117D01*
G01X97200Y-101117D02*
Y-83617D01*
X102440D01*
X104187Y-84492D01*
X105497Y-86534D01*
X105934Y-88867D01*
X105497Y-91200D01*
X104405Y-92950D01*
X102440Y-93826D01*
X97200D01*
G01X123870Y-85076D02*
X122560Y-84200D01*
X121032Y-83617D01*
X119285D01*
X117320Y-84492D01*
X115792Y-85950D01*
X114700Y-87701D01*
X113827Y-90617D01*
X113608Y-93242D01*
X114045Y-95867D01*
X114700Y-97617D01*
X116010Y-99367D01*
X117539Y-100534D01*
X119067Y-101117D01*
X120595D01*
X122124Y-100534D01*
X123434Y-99659D01*
X124526Y-98493D01*
G01X138313Y-91784D02*
X139187Y-90909D01*
X139842Y-89451D01*
X140279Y-87408D01*
X139842Y-85659D01*
X138969Y-84492D01*
X137440Y-83617D01*
X131545D01*
Y-101117D01*
X138750D01*
X140279Y-99951D01*
X141152Y-98200D01*
X141589Y-96159D01*
X141152Y-94117D01*
X139842Y-92367D01*
X138313Y-91784D01*
X131545D01*
G01X147517Y-106950D02*
X160617D01*
G01X166545Y-101117D02*
Y-83617D01*
X176589Y-101117D01*
Y-83617D01*
G01X189067Y-101117D02*
X187320Y-100825D01*
X185792Y-99659D01*
X184482Y-97909D01*
X183608Y-95867D01*
X183172Y-93534D01*
Y-91200D01*
X183608Y-88867D01*
X184482Y-86825D01*
X185792Y-85076D01*
X187320Y-83909D01*
X189067Y-83617D01*
X190813Y-83909D01*
X192342Y-85076D01*
X193652Y-86825D01*
X194526Y-88867D01*
X194962Y-91200D01*
Y-93534D01*
X194526Y-95867D01*
X193652Y-97909D01*
X192342Y-99659D01*
X190813Y-100825D01*
X189067Y-101117D01*
G01X258282Y-143784D02*
X260029Y-145242D01*
X261994Y-146117D01*
X263740D01*
X265487Y-145242D01*
X266797Y-143784D01*
X267452Y-141742D01*
X267015Y-139701D01*
X265924Y-137950D01*
X263959Y-136784D01*
X261339Y-136200D01*
X259810Y-135034D01*
X259155Y-132992D01*
X259592Y-130950D01*
X260684Y-129492D01*
X262212Y-128617D01*
X263740D01*
X265269Y-129200D01*
X266579Y-130659D01*
G01X282113Y-136784D02*
X282987Y-135909D01*
X283642Y-134451D01*
X284079Y-132408D01*
X283642Y-130659D01*
X282769Y-129492D01*
X281240Y-128617D01*
X275345D01*
Y-146117D01*
X282550D01*
X284079Y-144951D01*
X284952Y-143200D01*
X285389Y-141159D01*
X284952Y-139117D01*
X283642Y-137367D01*
X282113Y-136784D01*
X275345D01*
G01X239908Y-83617D02*
X245367Y-101117D01*
X250826Y-83617D01*
G01X267234Y-101117D02*
X258500D01*
Y-83617D01*
X267234D01*
G01X263740Y-92075D02*
X258500D01*
G01X276000Y-101117D02*
Y-83617D01*
X281459D01*
X283205Y-84492D01*
X284297Y-85659D01*
X284734Y-87992D01*
X284297Y-90326D01*
X282987Y-91784D01*
X281459Y-92659D01*
X276000D01*
G01X281459D02*
X284734Y-101117D01*
G01X297867Y-101700D02*
X297430Y-101409D01*
Y-100825D01*
X297867Y-100534D01*
X298304Y-100825D01*
Y-101409D01*
X297867Y-101700D01*
G01X377817Y-128617D02*
Y-146117D01*
G01X372795Y-128617D02*
X382839D01*
G01X389640Y-146117D02*
Y-128617D01*
X395317Y-143200D01*
X400994Y-128617D01*
Y-146117D01*
G01X407358D02*
X412817Y-128617D01*
X418276Y-146117D01*
G01X416310Y-139992D02*
X409323D01*
G01X425732Y-143784D02*
X427479Y-145242D01*
X429444Y-146117D01*
X431190D01*
X432937Y-145242D01*
X434247Y-143784D01*
X434902Y-141742D01*
X434465Y-139701D01*
X433374Y-137950D01*
X431409Y-136784D01*
X428789Y-136200D01*
X427260Y-135034D01*
X426605Y-132992D01*
X427042Y-130950D01*
X428134Y-129492D01*
X429662Y-128617D01*
X431190D01*
X432719Y-129200D01*
X434029Y-130659D01*
G01X443014Y-146117D02*
Y-128617D01*
G01X451310D02*
X443014Y-139409D01*
G01X452620Y-146117D02*
X446725Y-134451D01*
G01X373450Y-83617D02*
Y-101117D01*
X382184D01*
G01X399247D02*
Y-89451D01*
G01Y-91492D02*
X398374Y-90326D01*
X397063Y-89742D01*
X395535Y-89451D01*
X394007Y-90034D01*
X392697Y-91200D01*
X391823Y-92950D01*
X391387Y-95284D01*
X391823Y-97617D01*
X392697Y-99367D01*
X394007Y-100534D01*
X395535Y-101117D01*
X397063Y-100825D01*
X398374Y-99951D01*
X399247Y-98784D01*
G01X408232Y-106367D02*
X409542Y-106950D01*
X411289Y-106367D01*
X412380Y-105201D01*
X413254Y-103742D01*
X414563Y-99076D01*
X417402Y-89451D01*
G01X410415D02*
X414563Y-99076D01*
G01X427042Y-93242D02*
X434029D01*
X433374Y-91200D01*
X432282Y-90034D01*
X430754Y-89451D01*
X429225Y-89742D01*
X427915Y-90617D01*
X427042Y-92659D01*
X426605Y-94409D01*
Y-96159D01*
X427042Y-97909D01*
X428134Y-99659D01*
X429444Y-100825D01*
X430972Y-101117D01*
X432500Y-100534D01*
X434029Y-98784D01*
G01X444760Y-101117D02*
Y-89451D01*
G01Y-91784D02*
X445852Y-90617D01*
X446944Y-89742D01*
X448472Y-89451D01*
X449563Y-89742D01*
X450874Y-90617D01*
G01X515564Y-101117D02*
Y-83617D01*
X519930D01*
X521677Y-84492D01*
X522987Y-85659D01*
X524079Y-87408D01*
X524952Y-89451D01*
X525170Y-92367D01*
X524952Y-95284D01*
X524079Y-97326D01*
X522987Y-99076D01*
X521677Y-100242D01*
X519930Y-101117D01*
X515564D01*
G01X534592Y-93242D02*
X541579D01*
X540924Y-91200D01*
X539832Y-90034D01*
X538304Y-89451D01*
X536775Y-89742D01*
X535465Y-90617D01*
X534592Y-92659D01*
X534155Y-94409D01*
Y-96159D01*
X534592Y-97909D01*
X535684Y-99659D01*
X536994Y-100825D01*
X538522Y-101117D01*
X540050Y-100534D01*
X541579Y-98784D01*
G01X552092Y-99076D02*
X553184Y-100242D01*
X554712Y-101117D01*
X556022D01*
X557332Y-100534D01*
X558205Y-99659D01*
X558642Y-98493D01*
X558424Y-96742D01*
X557550Y-95867D01*
X553620Y-94117D01*
X552747Y-92075D01*
X553184Y-90617D01*
X554057Y-89742D01*
X555367Y-89451D01*
X556677Y-89742D01*
X557987Y-90617D01*
G01X572867Y-89451D02*
Y-101117D01*
G01Y-84784D02*
X572430Y-84492D01*
Y-83909D01*
X572867Y-83617D01*
X573304Y-83909D01*
Y-84492D01*
X572867Y-84784D01*
G01X587310Y-105492D02*
X588839Y-106659D01*
X590585Y-106950D01*
X592113Y-106659D01*
X593424Y-105201D01*
X594297Y-103159D01*
Y-89451D01*
G01Y-91784D02*
X593424Y-90617D01*
X592113Y-89742D01*
X590585Y-89451D01*
X588839Y-90034D01*
X587747Y-91200D01*
X586873Y-93242D01*
X586437Y-95284D01*
X586655Y-97034D01*
X587529Y-99076D01*
X588839Y-100534D01*
X590585Y-101117D01*
X591895Y-100825D01*
X593424Y-99659D01*
X594297Y-98493D01*
G01X604155Y-101117D02*
Y-89451D01*
G01Y-92367D02*
X605029Y-90909D01*
X606339Y-89742D01*
X608085Y-89451D01*
X609613Y-89742D01*
X610924Y-90909D01*
X611579Y-92950D01*
Y-101117D01*
G01X622092Y-93242D02*
X629079D01*
X628424Y-91200D01*
X627332Y-90034D01*
X625804Y-89451D01*
X624275Y-89742D01*
X622965Y-90617D01*
X622092Y-92659D01*
X621655Y-94409D01*
Y-96159D01*
X622092Y-97909D01*
X623184Y-99659D01*
X624494Y-100825D01*
X626022Y-101117D01*
X627550Y-100534D01*
X629079Y-98784D01*
G01X639810Y-101117D02*
Y-89451D01*
G01Y-91784D02*
X640902Y-90617D01*
X641994Y-89742D01*
X643522Y-89451D01*
X644613Y-89742D01*
X645924Y-90617D01*
G01X559969Y-128617D02*
X568265D01*
X559969Y-146117D01*
X568265D01*
G01X581617D02*
X579870Y-145825D01*
X578342Y-144659D01*
X577032Y-142909D01*
X576158Y-140867D01*
X575722Y-138534D01*
Y-136200D01*
X576158Y-133867D01*
X577032Y-131825D01*
X578342Y-130076D01*
X579870Y-128909D01*
X581617Y-128617D01*
X583363Y-128909D01*
X584892Y-130076D01*
X586202Y-131825D01*
X587076Y-133867D01*
X587512Y-136200D01*
Y-138534D01*
X587076Y-140867D01*
X586202Y-142909D01*
X584892Y-144659D01*
X583363Y-145825D01*
X581617Y-146117D01*
G01X603484D02*
X594750D01*
Y-128617D01*
X603484D01*
G01X599990Y-137075D02*
X594750D01*
G01X686567Y-128617D02*
X684820Y-129200D01*
X683510Y-130659D01*
X682637Y-132408D01*
X681982Y-134742D01*
X681764Y-137367D01*
X681982Y-139992D01*
X682637Y-142326D01*
X683510Y-144076D01*
X684820Y-145534D01*
X686567Y-146117D01*
X688313Y-145534D01*
X689624Y-144076D01*
X690497Y-142326D01*
X691152Y-139992D01*
X691370Y-137367D01*
X691152Y-134742D01*
X690497Y-132408D01*
X689624Y-130659D01*
X688313Y-129200D01*
X686567Y-128617D01*
G01X699919Y-131534D02*
X701229Y-129784D01*
X702757Y-128909D01*
X704504Y-128617D01*
X706687Y-129200D01*
X708215Y-130659D01*
X708652Y-132408D01*
X708434Y-134159D01*
X707560Y-135617D01*
X703194Y-138534D01*
X701229Y-140575D01*
X699919Y-143493D01*
X699482Y-146117D01*
X708652D01*
G01X717637Y-146700D02*
X725497Y-128617D01*
G01X739067D02*
X737320Y-129200D01*
X736010Y-130659D01*
X735137Y-132408D01*
X734482Y-134742D01*
X734264Y-137367D01*
X734482Y-139992D01*
X735137Y-142326D01*
X736010Y-144076D01*
X737320Y-145534D01*
X739067Y-146117D01*
X740813Y-145534D01*
X742124Y-144076D01*
X742997Y-142326D01*
X743652Y-139992D01*
X743870Y-137367D01*
X743652Y-134742D01*
X742997Y-132408D01*
X742124Y-130659D01*
X740813Y-129200D01*
X739067Y-128617D01*
G01X756130Y-146117D02*
X756567Y-142326D01*
X757222Y-139117D01*
X758095Y-136200D01*
X759187Y-132992D01*
X760934Y-128617D01*
X752200D01*
G01X770137Y-146700D02*
X777997Y-128617D01*
G01X787419Y-131534D02*
X788729Y-129784D01*
X790257Y-128909D01*
X792004Y-128617D01*
X794187Y-129200D01*
X795715Y-130659D01*
X796152Y-132408D01*
X795934Y-134159D01*
X795060Y-135617D01*
X790694Y-138534D01*
X788729Y-140575D01*
X787419Y-143493D01*
X786982Y-146117D01*
X796152D01*
G01X809067Y-128617D02*
X807320Y-129200D01*
X806010Y-130659D01*
X805137Y-132408D01*
X804482Y-134742D01*
X804264Y-137367D01*
X804482Y-139992D01*
X805137Y-142326D01*
X806010Y-144076D01*
X807320Y-145534D01*
X809067Y-146117D01*
X810813Y-145534D01*
X812124Y-144076D01*
X812997Y-142326D01*
X813652Y-139992D01*
X813870Y-137367D01*
X813652Y-134742D01*
X812997Y-132408D01*
X812124Y-130659D01*
X810813Y-129200D01*
X809067Y-128617D01*
G01X826567Y-146117D02*
Y-128617D01*
X823947Y-132117D01*
G01Y-146117D02*
X829187D01*
G01X843630D02*
X844067Y-142326D01*
X844722Y-139117D01*
X845595Y-136200D01*
X846687Y-132992D01*
X848434Y-128617D01*
X839700D01*
G01X734264Y-101117D02*
Y-83617D01*
X738630D01*
X740377Y-84492D01*
X741687Y-85659D01*
X742779Y-87408D01*
X743652Y-89451D01*
X743870Y-92367D01*
X743652Y-95284D01*
X742779Y-97326D01*
X741687Y-99076D01*
X740377Y-100242D01*
X738630Y-101117D01*
X734264D01*
G01X760497D02*
Y-89451D01*
G01Y-91492D02*
X759624Y-90326D01*
X758313Y-89742D01*
X756785Y-89451D01*
X755257Y-90034D01*
X753947Y-91200D01*
X753073Y-92950D01*
X752637Y-95284D01*
X753073Y-97617D01*
X753947Y-99367D01*
X755257Y-100534D01*
X756785Y-101117D01*
X758313Y-100825D01*
X759624Y-99951D01*
X760497Y-98784D01*
G01X774067Y-83617D02*
Y-101117D01*
G01X771010Y-89451D02*
X777124D01*
G01X788292Y-93242D02*
X795279D01*
X794624Y-91200D01*
X793532Y-90034D01*
X792004Y-89451D01*
X790475Y-89742D01*
X789165Y-90617D01*
X788292Y-92659D01*
X787855Y-94409D01*
Y-96159D01*
X788292Y-97909D01*
X789384Y-99659D01*
X790694Y-100825D01*
X792222Y-101117D01*
X793750Y-100534D01*
X795279Y-98784D01*
G54D29*
X36930Y38484D03*
X41654D03*
X46378D03*
Y55414D03*
X41654D03*
X36930D03*
M02*
